# S9S_MB_2U (Grand Teton) — schematic netlist excerpt (pin names and nets, part order shuffled) for the footprints in the layout excerpt that follows; sources: Cadence DE-HDL packaged netlist, KiCad conversion of 03242023_DA0F0TMBIJ0_F0T_Motherboard_J_brd_V01_OCP.brd

R4720  Q_RES  0 5% CHIP  pkg 0402LF  page 240 : A = FM_AC_PWR_BTN_N ; B = FM_AC_PWR_BTN_R_N

(kicad_pcb
	(version 20260206)
	(generator "pcbnew")
	(generator_version "10.0")
	(general
		(thickness 1.6)
		(legacy_teardrops no)
	)
	(paper "A4")
	(title_block
		(title "03242023_DA0F0TMBIJ0_F0T_Motherboard_J_brd_V01_OCP.brd")
		(comment 1 "Grand Teton / footprints 424-424 of 6105")
	)
	(layers
		(0 "F.Cu" signal "TOP")
		(4 "In1.Cu" signal "GND")
		(6 "In2.Cu" signal "IN1")
		(8 "In3.Cu" signal "GND1")
		(10 "In4.Cu" signal "IN2")
		(12 "In5.Cu" signal "GND2")
		(14 "In6.Cu" signal "IN3")
		(16 "In7.Cu" signal "GND3")
		(18 "In8.Cu" signal "VCC")
		(20 "In9.Cu" signal "VCC1")
		(22 "In10.Cu" signal "GND4")
		(24 "In11.Cu" signal "IN4")
		(26 "In12.Cu" signal "GND5")
		(28 "In13.Cu" signal "IN5")
		(30 "In14.Cu" signal "GND6")
		(32 "In15.Cu" signal "IN6")
		(34 "In16.Cu" signal "GND7")
		(2 "B.Cu" signal "BOTTOM")
		(9 "F.Adhes" user "F.Adhesive")
		(11 "B.Adhes" user "B.Adhesive")
		(13 "F.Paste" user "Package Geometry/Pastemask Top")
		(15 "B.Paste" user "Package Geometry/Pastemask Bottom")
		(5 "F.SilkS" user "Ref Des/Silkscreen Top")
		(7 "B.SilkS" user "Ref Des/Silkscreen Bottom")
		(1 "F.Mask" user "Board Geometry/Soldermask Top")
		(3 "B.Mask" user "Board Geometry/Soldermask Bottom")
		(17 "Dwgs.User" user "User.Drawings")
		(19 "Cmts.User" user "User.Comments")
		(21 "Eco1.User" user "User.Eco1")
		(23 "Eco2.User" user "User.Eco2")
		(25 "Edge.Cuts" user "Board Geometry/Outline")
		(27 "Margin" user)
		(31 "F.CrtYd" user "Package Geometry/Place Bound Top")
		(29 "B.CrtYd" user "Package Geometry/Place Bound Bottom")
		(35 "F.Fab" user "Ref Des/Assembly Top")
		(33 "B.Fab" user "Ref Des/Assembly Bottom")
	)
	(footprint ""
		(layer "F.Cu")
		(at 150.68296 -22.73808 90)
		(property "Reference" "R4720"
			(at 0 0 90)
			(layer "F.SilkS")
			(hide yes)
			(effects
				(font
					(size 1.27 1.27)
				)
			)
		)
		(property "Value" ""
			(at 0 0 90)
			(layer "F.Fab")
			(effects
				(font
					(size 1.27 1.27)
				)
			)
		)
		(duplicate_pad_numbers_are_jumpers no)
		(fp_line
			(start 0.7874 -0.4064)
			(end 0.7874 0.4064)
			(stroke
				(width 0.1524)
				(type default)
			)
			(layer "F.SilkS")
		)
		(fp_line
			(start -0.7874 -0.4064)
			(end 0.7874 -0.4064)
			(stroke
				(width 0.1524)
				(type default)
			)
			(layer "F.SilkS")
		)
		(fp_line
			(start 0.7874 0.4064)
			(end -0.7874 0.4064)
			(stroke
				(width 0.1524)
				(type default)
			)
			(layer "F.SilkS")
		)
		(fp_line
			(start -0.7874 0.4064)
			(end -0.7874 -0.4064)
			(stroke
				(width 0.1524)
				(type default)
			)
			(layer "F.SilkS")
		)
		(fp_line
			(start -0.12065 -0.305054)
			(end -0.12065 -0.2794)
			(stroke
				(width 0.1)
				(type default)
			)
			(layer "F.Fab")
		)
		(fp_line
			(start -0.67945 -0.305054)
			(end -0.12065 -0.305054)
			(stroke
				(width 0.1)
				(type default)
			)
			(layer "F.Fab")
		)
		(fp_line
			(start 0.67945 -0.3048)
			(end 0.67945 0.3048)
			(stroke
				(width 0.1)
				(type default)
			)
			(layer "F.Fab")
		)
		(fp_line
			(start 0.12065 -0.3048)
			(end 0.67945 -0.3048)
			(stroke
				(width 0.1)
				(type default)
			)
			(layer "F.Fab")
		)
		(fp_line
			(start 0.12065 -0.2794)
			(end 0.12065 -0.3048)
			(stroke
				(width 0.1)
				(type default)
			)
			(layer "F.Fab")
		)
		(fp_line
			(start -0.12065 -0.2794)
			(end 0.12065 -0.2794)
			(stroke
				(width 0.1)
				(type default)
			)
			(layer "F.Fab")
		)
		(fp_line
			(start 0.120396 0.2794)
			(end -0.12065 0.2794)
			(stroke
				(width 0.1)
				(type default)
			)
			(layer "F.Fab")
		)
		(fp_line
			(start -0.12065 0.2794)
			(end -0.12065 0.3048)
			(stroke
				(width 0.1)
				(type default)
			)
			(layer "F.Fab")
		)
		(fp_line
			(start 0.67945 0.3048)
			(end 0.120396 0.3048)
			(stroke
				(width 0.1)
				(type default)
			)
			(layer "F.Fab")
		)
		(fp_line
			(start 0.120396 0.3048)
			(end 0.120396 0.2794)
			(stroke
				(width 0.1)
				(type default)
			)
			(layer "F.Fab")
		)
		(fp_line
			(start -0.12065 0.3048)
			(end -0.67945 0.3048)
			(stroke
				(width 0.1)
				(type default)
			)
			(layer "F.Fab")
		)
		(fp_line
			(start -0.67945 0.3048)
			(end -0.67945 -0.305054)
			(stroke
				(width 0.1)
				(type default)
			)
			(layer "F.Fab")
		)
		(pad "1" smd circle
			(at -0.40005 0 90)
			(size 0 0)
			(layers "F.Cu" "F.Mask" "F.Paste")
			(net "FM_AC_PWR_BTN_N")
		)
		(pad "2" smd circle
			(at 0.40005 0 90)
			(size 0 0)
			(layers "F.Cu" "F.Mask" "F.Paste")
			(net "FM_AC_PWR_BTN_R_N")
		)
	)
)
